(kicad_pcb
	(version 20221018)
	(generator pcbnew)
	(general
    (thickness 1.6)
  )
	(paper "A4")
	(title_block
    (title "NUC Computer Cluster Power Breakout HW")
    (date "2023-10-18")
    (rev "1.4.3")
    (company "Antmicro Ltd.")
		(comment 9 "footprints 213-213 of 234")
	)
	(layers
    (0 "F.Cu" mixed)
    (1 "In1.Cu" power)
    (2 "In2.Cu" mixed)
    (31 "B.Cu" power)
    (32 "B.Adhes" user "B.Adhesive")
    (33 "F.Adhes" user "F.Adhesive")
    (34 "B.Paste" user)
    (35 "F.Paste" user)
    (36 "B.SilkS" user "B.Silkscreen")
    (37 "F.SilkS" user "F.Silkscreen")
    (38 "B.Mask" user)
    (39 "F.Mask" user)
    (40 "Dwgs.User" user "User.Drawings")
    (41 "Cmts.User" user "User.Comments")
    (42 "Eco1.User" user "User.Eco1")
    (43 "Eco2.User" user "User.Eco2")
    (44 "Edge.Cuts" user)
    (45 "Margin" user)
    (46 "B.CrtYd" user "B.Courtyard")
    (47 "F.CrtYd" user "F.Courtyard")
    (48 "B.Fab" user)
    (49 "F.Fab" user)
  )
	(footprint "antmicro-footprints:C_0402_1005Metric" (layer "F.Cu")
    (at 149.935 103.7)
    (descr "Capacitor SMD 0402")
    (tags "capacitor SMD 0402")
    (property "Author" "Antmicro")
    (property "Dielectric" "X5R")
    (property "License" "Apache-2.0")
    (property "MPN" "GRM155R61H104KE14D")
    (property "Manufacturer" "Murata")
    (property "Sheetfile" "pow-cycl-curr-meas.kicad_sch")
    (property "Sheetname" "Power Cycling & Current Measurement")
    (property "Val" "100n")
    (property "Voltage" "50V")
    (property "ki_description" "SMD Multilayer Ceramic Capacitor, 0.1 µF, 50 V, 0402 [1005 Metric], ± 10%, X5R, GRM Series")
    (property "ki_keywords" "0402, SMT, CAPACITOR, PASSIVE, CERAMIC, MLCC")
    (attr smd)
    (fp_text reference "C37" (at 2.065 0.15) (layer "F.SilkS")
        (effects (font (size 0.7 0.7) (thickness 0.15)))
    )
    (fp_text value "C_100n_0402" (at 0 1.17) (layer "F.Fab") hide
        (effects (font (size 1 1) (thickness 0.15)))
    )
    (fp_text user "License: Apache-2.0" (at -0.939 5.799) (layer "F.Fab") hide
        (effects (font (size 0.7 0.7) (thickness 0.15)) (justify left bottom))
    )
    (fp_text user "Author: Antmicro" (at -0.939 3.399) (layer "F.Fab") hide
        (effects (font (size 0.7 0.7) (thickness 0.15)) (justify left bottom))
    )
    (fp_text user "${REFERENCE}" (at 0 0) (layer "F.Fab")
        (effects (font (size 0.25 0.25) (thickness 0.04)))
    )
    (fp_rect (start -0.925 -0.47) (end 0.925 0.47)
      (stroke (width 0.05) (type default)) (fill none) (layer "F.CrtYd"))
    (fp_line (start -0.494 -0.25) (end 0.504 -0.25)
      (stroke (width 0.15) (type solid)) (layer "F.Fab"))
    (fp_line (start -0.494 0.248) (end -0.494 -0.25)
      (stroke (width 0.15) (type solid)) (layer "F.Fab"))
    (fp_line (start 0.504 -0.25) (end 0.504 0.248)
      (stroke (width 0.15) (type solid)) (layer "F.Fab"))
    (fp_line (start 0.504 0.248) (end -0.494 0.248)
      (stroke (width 0.15) (type solid)) (layer "F.Fab"))
    (pad "1" smd roundrect (at -0.48 0) (size 0.59 0.64) (layers "F.Cu" "F.Paste" "F.Mask") (roundrect_rratio 0.25)
      (net 4 "GND") (pintype "passive"))
    (pad "2" smd roundrect (at 0.48 0) (size 0.59 0.64) (layers "F.Cu" "F.Paste" "F.Mask") (roundrect_rratio 0.25)
      (net 34 "Net-(U14-REF)") (pintype "passive"))
  )
)
